# T6G (Grand Teton) — schematic netlist excerpt (pin names and nets, part order shuffled) for the footprints in the layout excerpt that follows; sources: Cadence DE-HDL packaged netlist, KiCad conversion of 04192023_DAF0TMB3IC0_F0TG_MB_C_brd_V02_OCP.brd

C742  Q_CAP_DIFFBUS  DIFF BUS_0.22UF 6.3V 20% X6S  pkg C0201  page 66 : \1\ = P5E_CPU1_P2_TX_C_DN<15> ; \2\ = P5E_CPU1_P2_TX_DN<15>
R8004  Q_RES  0 5% CHIP  pkg 0402LF  page 245 : A = PRSNT_SWB_ISO_N ; B = PRSNT_SWB_ISO_R1_N
C1507  Q_CAP  0.1UF 16V 10% X7R  pkg C0402  page 172 : A = PVDD18_S5_P0 ; B = GND

(kicad_pcb
	(version 20260206)
	(generator "pcbnew")
	(generator_version "10.0")
	(general
		(thickness 1.6)
		(legacy_teardrops no)
	)
	(paper "A4")
	(title_block
		(title "04192023_DAF0TMB3IC0_F0TG_MB_C_brd_V02_OCP.brd")
		(comment 1 "Grand Teton / footprints 2923-2925 of 8354")
	)
	(layers
		(0 "F.Cu" signal "TOP")
		(4 "In1.Cu" signal "GND")
		(6 "In2.Cu" signal "IN1")
		(8 "In3.Cu" signal "GND1")
		(10 "In4.Cu" signal "IN2")
		(12 "In5.Cu" signal "GND2")
		(14 "In6.Cu" signal "IN3")
		(16 "In7.Cu" signal "GND3")
		(18 "In8.Cu" signal "VCC")
		(20 "In9.Cu" signal "VCC1")
		(22 "In10.Cu" signal "GND4")
		(24 "In11.Cu" signal "IN4")
		(26 "In12.Cu" signal "GND5")
		(28 "In13.Cu" signal "IN5")
		(30 "In14.Cu" signal "GND6")
		(32 "In15.Cu" signal "IN6")
		(34 "In16.Cu" signal "GND7")
		(2 "B.Cu" signal "BOTTOM")
		(9 "F.Adhes" user "F.Adhesive")
		(11 "B.Adhes" user "B.Adhesive")
		(13 "F.Paste" user "Package Geometry/Pastemask Top")
		(15 "B.Paste" user "Package Geometry/Pastemask Bottom")
		(5 "F.SilkS" user "Ref Des/Silkscreen Top")
		(7 "B.SilkS" user "Ref Des/Silkscreen Bottom")
		(1 "F.Mask" user "Board Geometry/Soldermask Top")
		(3 "B.Mask" user "Board Geometry/Soldermask Bottom")
		(17 "Dwgs.User" user "User.Drawings")
		(19 "Cmts.User" user "User.Comments")
		(21 "Eco1.User" user "User.Eco1")
		(23 "Eco2.User" user "User.Eco2")
		(25 "Edge.Cuts" user "Board Geometry/Outline")
		(27 "Margin" user)
		(31 "F.CrtYd" user "Package Geometry/Place Bound Top")
		(29 "B.CrtYd" user "Package Geometry/Place Bound Bottom")
		(35 "F.Fab" user "Ref Des/Assembly Top")
		(33 "B.Fab" user "Ref Des/Assembly Bottom")
	)
	(footprint ""
		(layer "F.Cu")
		(at 185.095642 -413.64408 90)
		(property "Reference" "R8004"
			(at 0 0 90)
			(layer "F.SilkS")
			(hide yes)
			(effects
				(font
					(size 1.27 1.27)
				)
			)
		)
		(property "Value" ""
			(at 0 0 90)
			(layer "F.Fab")
			(effects
				(font
					(size 1.27 1.27)
				)
			)
		)
		(duplicate_pad_numbers_are_jumpers no)
		(fp_line
			(start 0.7874 -0.4064)
			(end 0.7874 0.4064)
			(stroke
				(width 0.1524)
				(type default)
			)
			(layer "F.SilkS")
		)
		(fp_line
			(start -0.7874 -0.4064)
			(end 0.7874 -0.4064)
			(stroke
				(width 0.1524)
				(type default)
			)
			(layer "F.SilkS")
		)
		(fp_line
			(start 0.7874 0.4064)
			(end -0.7874 0.4064)
			(stroke
				(width 0.1524)
				(type default)
			)
			(layer "F.SilkS")
		)
		(fp_line
			(start -0.7874 0.4064)
			(end -0.7874 -0.4064)
			(stroke
				(width 0.1524)
				(type default)
			)
			(layer "F.SilkS")
		)
		(fp_line
			(start -0.12065 -0.305054)
			(end -0.12065 -0.2794)
			(stroke
				(width 0.1)
				(type default)
			)
			(layer "F.Fab")
		)
		(fp_line
			(start -0.67945 -0.305054)
			(end -0.12065 -0.305054)
			(stroke
				(width 0.1)
				(type default)
			)
			(layer "F.Fab")
		)
		(fp_line
			(start 0.67945 -0.3048)
			(end 0.67945 0.3048)
			(stroke
				(width 0.1)
				(type default)
			)
			(layer "F.Fab")
		)
		(fp_line
			(start 0.12065 -0.3048)
			(end 0.67945 -0.3048)
			(stroke
				(width 0.1)
				(type default)
			)
			(layer "F.Fab")
		)
		(fp_line
			(start 0.12065 -0.2794)
			(end 0.12065 -0.3048)
			(stroke
				(width 0.1)
				(type default)
			)
			(layer "F.Fab")
		)
		(fp_line
			(start -0.12065 -0.2794)
			(end 0.12065 -0.2794)
			(stroke
				(width 0.1)
				(type default)
			)
			(layer "F.Fab")
		)
		(fp_line
			(start 0.120396 0.2794)
			(end -0.12065 0.2794)
			(stroke
				(width 0.1)
				(type default)
			)
			(layer "F.Fab")
		)
		(fp_line
			(start -0.12065 0.2794)
			(end -0.12065 0.3048)
			(stroke
				(width 0.1)
				(type default)
			)
			(layer "F.Fab")
		)
		(fp_line
			(start 0.67945 0.3048)
			(end 0.120396 0.3048)
			(stroke
				(width 0.1)
				(type default)
			)
			(layer "F.Fab")
		)
		(fp_line
			(start 0.120396 0.3048)
			(end 0.120396 0.2794)
			(stroke
				(width 0.1)
				(type default)
			)
			(layer "F.Fab")
		)
		(fp_line
			(start -0.12065 0.3048)
			(end -0.67945 0.3048)
			(stroke
				(width 0.1)
				(type default)
			)
			(layer "F.Fab")
		)
		(fp_line
			(start -0.67945 0.3048)
			(end -0.67945 -0.305054)
			(stroke
				(width 0.1)
				(type default)
			)
			(layer "F.Fab")
		)
		(pad "1" smd circle
			(at -0.40005 0 90)
			(size 0 0)
			(layers "F.Cu" "F.Mask" "F.Paste")
			(net "PRSNT_SWB_ISO_N")
		)
		(pad "2" smd circle
			(at 0.40005 0 90)
			(size 0 0)
			(layers "F.Cu" "F.Mask" "F.Paste")
			(net "PRSNT_SWB_ISO_R1_N")
		)
	)
	(footprint ""
		(layer "F.Cu")
		(at 169.368724 -380.385828)
		(property "Reference" "C742"
			(at 0 0 0)
			(layer "F.SilkS")
			(hide yes)
			(effects
				(font
					(size 1.27 1.27)
				)
			)
		)
		(property "Value" ""
			(at 0 0 0)
			(layer "F.Fab")
			(effects
				(font
					(size 1.27 1.27)
				)
			)
		)
		(duplicate_pad_numbers_are_jumpers no)
		(fp_line
			(start -0.299974 -0.150114)
			(end 0.299974 -0.150114)
			(stroke
				(width 0.1)
				(type default)
			)
			(layer "F.Fab")
		)
		(fp_line
			(start -0.299974 0.150114)
			(end -0.299974 -0.150114)
			(stroke
				(width 0.1)
				(type default)
			)
			(layer "F.Fab")
		)
		(fp_line
			(start 0.299974 -0.150114)
			(end 0.299974 0.150114)
			(stroke
				(width 0.1)
				(type default)
			)
			(layer "F.Fab")
		)
		(fp_line
			(start 0.299974 0.150114)
			(end -0.299974 0.150114)
			(stroke
				(width 0.1)
				(type default)
			)
			(layer "F.Fab")
		)
		(pad "1" smd rect
			(at -0.2667 0)
			(size 0.3048 0.381)
			(layers "F.Cu" "F.Mask" "F.Paste")
			(net "P5E_CPU1_P2_TX_C_DN<15>")
		)
		(pad "2" smd rect
			(at 0.2667 0)
			(size 0.3048 0.381)
			(layers "F.Cu" "F.Mask" "F.Paste")
			(net "P5E_CPU1_P2_TX_DN<15>")
		)
	)
	(footprint ""
		(layer "F.Cu")
		(at 271.585944 -100.446078 -90)
		(property "Reference" "C1507"
			(at 0 0 270)
			(layer "F.SilkS")
			(hide yes)
			(effects
				(font
					(size 1.27 1.27)
				)
			)
		)
		(property "Value" ""
			(at 0 0 270)
			(layer "F.Fab")
			(effects
				(font
					(size 1.27 1.27)
				)
			)
		)
		(duplicate_pad_numbers_are_jumpers no)
		(fp_line
			(start -0.7874 0.4064)
			(end -0.7874 -0.4064)
			(stroke
				(width 0.1524)
				(type default)
			)
			(layer "F.SilkS")
		)
		(fp_line
			(start 0.7874 0.4064)
			(end -0.7874 0.4064)
			(stroke
				(width 0.1524)
				(type default)
			)
			(layer "F.SilkS")
		)
		(fp_line
			(start -0.7874 -0.4064)
			(end 0.7874 -0.4064)
			(stroke
				(width 0.1524)
				(type default)
			)
			(layer "F.SilkS")
		)
		(fp_line
			(start 0.7874 -0.4064)
			(end 0.7874 0.4064)
			(stroke
				(width 0.1524)
				(type default)
			)
			(layer "F.SilkS")
		)
		(fp_line
			(start -0.67945 0.3048)
			(end -0.67945 -0.305054)
			(stroke
				(width 0.1)
				(type default)
			)
			(layer "F.Fab")
		)
		(fp_line
			(start -0.12065 0.3048)
			(end -0.67945 0.3048)
			(stroke
				(width 0.1)
				(type default)
			)
			(layer "F.Fab")
		)
		(fp_line
			(start 0.120396 0.3048)
			(end 0.120396 0.2794)
			(stroke
				(width 0.1)
				(type default)
			)
			(layer "F.Fab")
		)
		(fp_line
			(start 0.67945 0.3048)
			(end 0.120396 0.3048)
			(stroke
				(width 0.1)
				(type default)
			)
			(layer "F.Fab")
		)
		(fp_line
			(start -0.12065 0.2794)
			(end -0.12065 0.3048)
			(stroke
				(width 0.1)
				(type default)
			)
			(layer "F.Fab")
		)
		(fp_line
			(start 0.120396 0.2794)
			(end -0.12065 0.2794)
			(stroke
				(width 0.1)
				(type default)
			)
			(layer "F.Fab")
		)
		(fp_line
			(start -0.12065 -0.2794)
			(end 0.12065 -0.2794)
			(stroke
				(width 0.1)
				(type default)
			)
			(layer "F.Fab")
		)
		(fp_line
			(start 0.12065 -0.2794)
			(end 0.12065 -0.3048)
			(stroke
				(width 0.1)
				(type default)
			)
			(layer "F.Fab")
		)
		(fp_line
			(start 0.12065 -0.3048)
			(end 0.67945 -0.3048)
			(stroke
				(width 0.1)
				(type default)
			)
			(layer "F.Fab")
		)
		(fp_line
			(start 0.67945 -0.3048)
			(end 0.67945 0.3048)
			(stroke
				(width 0.1)
				(type default)
			)
			(layer "F.Fab")
		)
		(fp_line
			(start -0.67945 -0.305054)
			(end -0.12065 -0.305054)
			(stroke
				(width 0.1)
				(type default)
			)
			(layer "F.Fab")
		)
		(fp_line
			(start -0.12065 -0.305054)
			(end -0.12065 -0.2794)
			(stroke
				(width 0.1)
				(type default)
			)
			(layer "F.Fab")
		)
		(pad "1" smd circle
			(at -0.40005 0 270)
			(size 0 0)
			(layers "F.Cu" "F.Mask" "F.Paste")
			(net "PVDD18_S5_P0")
		)
		(pad "2" smd circle
			(at 0.40005 0 270)
			(size 0 0)
			(layers "F.Cu" "F.Mask" "F.Paste")
			(net "GND")
		)
	)
)
